# S9S_MB_2U (Grand Teton) — schematic netlist excerpt (pin names and nets, part order shuffled) for the footprints in the layout excerpt that follows; sources: Cadence DE-HDL packaged netlist, KiCad conversion of 03242023_DA0F0TMBIJ0_F0T_Motherboard_J_brd_V01_OCP.brd

C267  Q_CAP  10UF 6.3V 20% X6S  pkg C0402  page 77 : A = PVCCIN_CPU1 ; B = GND

PU80  RS53318LR  IC  pkg QFN21_4X3  page 299
  BST  = SW_PVPP_HBM_CPU1_BST
  AGND  = GND
  CS  = PVPP_HBM_CPU1_CS
  MODE  = PVPP_HBM_CPU1_MODE
  REF  = PVPP_HBM_CPU1_REF
  RTN  = SH_PVPP_HBM_CPU1_N
  FB  = PVPP_HBM_CPU1_FB
  EN  = FM_PVPP_HBM_CPU1_EN
  PGOOD  = PWRGD_PVPP_HBM_CPU1_R
  VIN1  = SW_P12V_PVCCIN_CPU1_FLT
  PGND  = GND
  VCC  = PVPP_HBM_CPU1_VCC
  SW  = SW_PVPP_HBM_CPU1_SW
  VIN2  = SW_P12V_PVCCIN_CPU1_FLT

(kicad_pcb
	(version 20260206)
	(generator "pcbnew")
	(generator_version "10.0")
	(general
		(thickness 1.6)
		(legacy_teardrops no)
	)
	(paper "A4")
	(title_block
		(title "03242023_DA0F0TMBIJ0_F0T_Motherboard_J_brd_V01_OCP.brd")
		(comment 1 "Grand Teton / footprints 1010-1011 of 6105")
	)
	(layers
		(0 "F.Cu" signal "TOP")
		(4 "In1.Cu" signal "GND")
		(6 "In2.Cu" signal "IN1")
		(8 "In3.Cu" signal "GND1")
		(10 "In4.Cu" signal "IN2")
		(12 "In5.Cu" signal "GND2")
		(14 "In6.Cu" signal "IN3")
		(16 "In7.Cu" signal "GND3")
		(18 "In8.Cu" signal "VCC")
		(20 "In9.Cu" signal "VCC1")
		(22 "In10.Cu" signal "GND4")
		(24 "In11.Cu" signal "IN4")
		(26 "In12.Cu" signal "GND5")
		(28 "In13.Cu" signal "IN5")
		(30 "In14.Cu" signal "GND6")
		(32 "In15.Cu" signal "IN6")
		(34 "In16.Cu" signal "GND7")
		(2 "B.Cu" signal "BOTTOM")
		(9 "F.Adhes" user "F.Adhesive")
		(11 "B.Adhes" user "B.Adhesive")
		(13 "F.Paste" user "Package Geometry/Pastemask Top")
		(15 "B.Paste" user "Package Geometry/Pastemask Bottom")
		(5 "F.SilkS" user "Ref Des/Silkscreen Top")
		(7 "B.SilkS" user "Ref Des/Silkscreen Bottom")
		(1 "F.Mask" user "Board Geometry/Soldermask Top")
		(3 "B.Mask" user "Board Geometry/Soldermask Bottom")
		(17 "Dwgs.User" user "User.Drawings")
		(19 "Cmts.User" user "User.Comments")
		(21 "Eco1.User" user "User.Eco1")
		(23 "Eco2.User" user "User.Eco2")
		(25 "Edge.Cuts" user "Board Geometry/Outline")
		(27 "Margin" user)
		(31 "F.CrtYd" user "Package Geometry/Place Bound Top")
		(29 "B.CrtYd" user "Package Geometry/Place Bound Bottom")
		(35 "F.Fab" user "Ref Des/Assembly Top")
		(33 "B.Fab" user "Ref Des/Assembly Bottom")
	)
	(footprint ""
		(layer "F.Cu")
		(at 125.715014 -358.460548)
		(property "Reference" "PU80"
			(at 3.758946 -0.80772 0)
			(unlocked yes)
			(layer "F.SilkS")
			(effects
				(font
					(size 0.7874 0.5842)
					(thickness 0.1524)
				)
				(justify left)
			)
		)
		(property "Value" ""
			(at 0 0 0)
			(layer "F.Fab")
			(effects
				(font
					(size 1.27 1.27)
				)
			)
		)
		(duplicate_pad_numbers_are_jumpers no)
		(fp_line
			(start -1.549908 -2.050034)
			(end -1.549908 -1.9812)
			(stroke
				(width 0.1524)
				(type default)
			)
			(layer "F.SilkS")
		)
		(fp_line
			(start -1.549908 1.9812)
			(end -1.549908 2.050034)
			(stroke
				(width 0.1524)
				(type default)
			)
			(layer "F.SilkS")
		)
		(fp_line
			(start -1.549908 2.050034)
			(end -0.5842 2.050034)
			(stroke
				(width 0.1524)
				(type default)
			)
			(layer "F.SilkS")
		)
		(fp_line
			(start -0.5842 -2.050034)
			(end -1.549908 -2.050034)
			(stroke
				(width 0.1524)
				(type default)
			)
			(layer "F.SilkS")
		)
		(fp_line
			(start 0 2.050034)
			(end 1.549908 2.050034)
			(stroke
				(width 0.1524)
				(type default)
			)
			(layer "F.SilkS")
		)
		(fp_line
			(start 1.549908 -2.050034)
			(end 0.5842 -2.050034)
			(stroke
				(width 0.1524)
				(type default)
			)
			(layer "F.SilkS")
		)
		(fp_line
			(start 1.549908 -1.9812)
			(end 1.549908 -2.050034)
			(stroke
				(width 0.1524)
				(type default)
			)
			(layer "F.SilkS")
		)
		(fp_line
			(start 1.549908 2.050034)
			(end 1.549908 1.9304)
			(stroke
				(width 0.1524)
				(type default)
			)
			(layer "F.SilkS")
		)
		(fp_poly
			(pts
				(xy -3.216402 -2.241042) (xy -3.216402 -1.225042) (xy -2.200402 -1.733042)
			)
			(stroke
				(width 0)
				(type default)
			)
			(fill yes)
			(layer "F.SilkS")
		)
		(fp_line
			(start -1.549908 -2.050034)
			(end -1.549908 2.050034)
			(stroke
				(width 0.1)
				(type default)
			)
			(layer "F.Fab")
		)
		(fp_line
			(start -1.549908 2.050034)
			(end 1.549908 2.050034)
			(stroke
				(width 0.1)
				(type default)
			)
			(layer "F.Fab")
		)
		(fp_line
			(start 1.549908 -2.050034)
			(end -1.549908 -2.050034)
			(stroke
				(width 0.1)
				(type default)
			)
			(layer "F.Fab")
		)
		(fp_line
			(start 1.549908 2.050034)
			(end 1.549908 -2.050034)
			(stroke
				(width 0.1)
				(type default)
			)
			(layer "F.Fab")
		)
		(fp_poly
			(pts
				(xy -2.9464 -2.208022) (xy -2.9464 -1.192022) (xy -1.9304 -1.700022)
			)
			(stroke
				(width 0)
				(type default)
			)
			(fill yes)
			(layer "F.Fab")
		)
		(pad "1" smd circle
			(at -1.35001 -1.700022)
			(size 0 0)
			(layers "F.Cu" "F.Mask" "F.Paste")
			(net "SW_PVPP_HBM_CPU1_BST")
		)
		(pad "2" smd rect
			(at -1.400048 -1.199896 90)
			(size 0.1778 0.8128)
			(layers "F.Cu" "F.Mask" "F.Paste")
			(net "GND")
		)
		(pad "3" smd rect
			(at -1.400048 -0.8001 90)
			(size 0.1778 0.8128)
			(layers "F.Cu" "F.Mask" "F.Paste")
			(net "PVPP_HBM_CPU1_CS")
		)
		(pad "4" smd rect
			(at -1.400048 -0.40005 90)
			(size 0.1778 0.8128)
			(layers "F.Cu" "F.Mask" "F.Paste")
			(net "PVPP_HBM_CPU1_MODE")
		)
		(pad "5" smd rect
			(at -1.400048 0 90)
			(size 0.1778 0.8128)
			(layers "F.Cu" "F.Mask" "F.Paste")
			(net "PVPP_HBM_CPU1_REF")
		)
		(pad "6" smd rect
			(at -1.400048 0.40005 90)
			(size 0.1778 0.8128)
			(layers "F.Cu" "F.Mask" "F.Paste")
			(net "SH_PVPP_HBM_CPU1_N")
		)
		(pad "7" smd rect
			(at -1.400048 0.8001 90)
			(size 0.1778 0.8128)
			(layers "F.Cu" "F.Mask" "F.Paste")
			(net "PVPP_HBM_CPU1_FB")
		)
		(pad "8" smd rect
			(at -1.400048 1.199896 90)
			(size 0.1778 0.8128)
			(layers "F.Cu" "F.Mask" "F.Paste")
			(net "FM_PVPP_HBM_CPU1_EN")
		)
		(pad "9" smd rect
			(at -1.400048 1.700022 90)
			(size 0.3048 0.8128)
			(layers "F.Cu" "F.Mask" "F.Paste")
			(net "PWRGD_PVPP_HBM_CPU1_R")
		)
		(pad "10" smd rect
			(at -0.299974 1.299972)
			(size 0.3048 2.0066)
			(layers "F.Cu" "F.Mask" "F.Paste")
			(net "SW_P12V_PVCCIN_CPU1_FLT")
		)
		(pad "11_18" smd circle
			(at 1.175004 0.275082)
			(size 0 0)
			(layers "F.Cu" "F.Mask" "F.Paste")
			(net "GND")
		)
		(pad "19" smd rect
			(at 1.400048 -1.700022 270)
			(size 0.3048 0.8128)
			(layers "F.Cu" "F.Mask" "F.Paste")
			(net "PVPP_HBM_CPU1_VCC")
		)
		(pad "20" smd rect
			(at 0.299974 -1.299972)
			(size 0.3048 2.0066)
			(layers "F.Cu" "F.Mask" "F.Paste")
			(net "SW_PVPP_HBM_CPU1_SW")
		)
		(pad "21" smd rect
			(at -0.299974 -1.299972)
			(size 0.3048 2.0066)
			(layers "F.Cu" "F.Mask" "F.Paste")
			(net "SW_P12V_PVCCIN_CPU1_FLT")
		)
	)
	(footprint ""
		(layer "F.Cu")
		(at 105.30713 -240.277142 90)
		(property "Reference" "C267"
			(at 0 0 90)
			(layer "F.SilkS")
			(hide yes)
			(effects
				(font
					(size 1.27 1.27)
				)
			)
		)
		(property "Value" ""
			(at 0 0 90)
			(layer "F.Fab")
			(effects
				(font
					(size 1.27 1.27)
				)
			)
		)
		(duplicate_pad_numbers_are_jumpers no)
		(fp_line
			(start 0.7874 -0.4064)
			(end 0.7874 0.4064)
			(stroke
				(width 0.1524)
				(type default)
			)
			(layer "F.SilkS")
		)
		(fp_line
			(start -0.7874 -0.4064)
			(end 0.7874 -0.4064)
			(stroke
				(width 0.1524)
				(type default)
			)
			(layer "F.SilkS")
		)
		(fp_line
			(start 0.7874 0.4064)
			(end -0.7874 0.4064)
			(stroke
				(width 0.1524)
				(type default)
			)
			(layer "F.SilkS")
		)
		(fp_line
			(start -0.7874 0.4064)
			(end -0.7874 -0.4064)
			(stroke
				(width 0.1524)
				(type default)
			)
			(layer "F.SilkS")
		)
		(fp_line
			(start -0.12065 -0.305054)
			(end -0.12065 -0.2794)
			(stroke
				(width 0.1)
				(type default)
			)
			(layer "F.Fab")
		)
		(fp_line
			(start -0.67945 -0.305054)
			(end -0.12065 -0.305054)
			(stroke
				(width 0.1)
				(type default)
			)
			(layer "F.Fab")
		)
		(fp_line
			(start 0.67945 -0.3048)
			(end 0.67945 0.3048)
			(stroke
				(width 0.1)
				(type default)
			)
			(layer "F.Fab")
		)
		(fp_line
			(start 0.12065 -0.3048)
			(end 0.67945 -0.3048)
			(stroke
				(width 0.1)
				(type default)
			)
			(layer "F.Fab")
		)
		(fp_line
			(start 0.12065 -0.2794)
			(end 0.12065 -0.3048)
			(stroke
				(width 0.1)
				(type default)
			)
			(layer "F.Fab")
		)
		(fp_line
			(start -0.12065 -0.2794)
			(end 0.12065 -0.2794)
			(stroke
				(width 0.1)
				(type default)
			)
			(layer "F.Fab")
		)
		(fp_line
			(start 0.120396 0.2794)
			(end -0.12065 0.2794)
			(stroke
				(width 0.1)
				(type default)
			)
			(layer "F.Fab")
		)
		(fp_line
			(start -0.12065 0.2794)
			(end -0.12065 0.3048)
			(stroke
				(width 0.1)
				(type default)
			)
			(layer "F.Fab")
		)
		(fp_line
			(start 0.67945 0.3048)
			(end 0.120396 0.3048)
			(stroke
				(width 0.1)
				(type default)
			)
			(layer "F.Fab")
		)
		(fp_line
			(start 0.120396 0.3048)
			(end 0.120396 0.2794)
			(stroke
				(width 0.1)
				(type default)
			)
			(layer "F.Fab")
		)
		(fp_line
			(start -0.12065 0.3048)
			(end -0.67945 0.3048)
			(stroke
				(width 0.1)
				(type default)
			)
			(layer "F.Fab")
		)
		(fp_line
			(start -0.67945 0.3048)
			(end -0.67945 -0.305054)
			(stroke
				(width 0.1)
				(type default)
			)
			(layer "F.Fab")
		)
		(pad "1" smd circle
			(at -0.40005 0 90)
			(size 0 0)
			(layers "F.Cu" "F.Mask" "F.Paste")
			(net "PVCCIN_CPU1")
		)
		(pad "2" smd circle
			(at 0.40005 0 90)
			(size 0 0)
			(layers "F.Cu" "F.Mask" "F.Paste")
			(net "GND")
		)
	)
)
